# T6G (Grand Teton) — schematic parts with pin connectivity, parts 8081–8081 of 8303; source: Cadence DE-HDL packaged netlist (pstxprt.dat, pstxnet.dat, pstchip.dat)

U25  GENOA_SP5  SOCKET6096_13568-001 IO  pkg SOCKET6096_93-4X120-45XA  page 10  (pins 3025-3360 of 6096)
  CD8  VSS_CD8  POWER  = GND
  CD9  MLB_DQS_H0  BI  = M_L_CPU0_SB_DQS_DP<0>
  CD10  VSS_CD10  POWER  = GND
  CD11  MLB_DATA3  BI  = M_L_CPU0_SB_DQ<3>
  CD12  VDD_11_S3_CD12  POWER  = PVDD11_S3_P0
  CD13  MHB_DQS_H0  BI  = M_H_CPU0_SB_DQS_DP<0>
  CD14  MHB_DATA3  BI  = M_H_CPU0_SB_DQ<3>
  CD15  VSS_CD15  POWER  = GND
  CD16  MJB_DQS_H0  BI  = M_J_CPU0_SB_DQS_DP<0>
  CD17  VSS_CD17  POWER  = GND
  CD18  MJB_DATA3  BI  = M_J_CPU0_SB_DQ<3>
  CD19  VDD_11_S3_CD19  POWER  = PVDD11_S3_P0
  CD20  MIB_DQS_H0  BI  = M_I_CPU0_SB_DQS_DP<0>
  CD21  MIB_DATA3  BI  = M_I_CPU0_SB_DQ<3>
  CD22  VSS_CD22  POWER  = GND
  CD23  VDDCR_CPU1_CD23  POWER  = PVDDCR_CPU1_P0
  CD24  VDDCR_CPU1_CD24  POWER  = PVDDCR_CPU1_P0
  CD25  VSS_CD25  POWER  = GND
  CD26  VDDCR_CPU1_CD26  POWER  = PVDDCR_CPU1_P0
  CD27  VDDCR_CPU1_CD27  POWER  = PVDDCR_CPU1_P0
  CD28  VSS_CD28  POWER  = GND
  CD29  VDDCR_CPU1_CD29  POWER  = PVDDCR_CPU1_P0
  CD30  VDDCR_CPU1_CD30  POWER  = PVDDCR_CPU1_P0
  CD31  VSS_CD31  POWER  = GND
  CD32  VDDCR_CPU1_CD32  POWER  = PVDDCR_CPU1_P0
  CD33  VDDCR_CPU1_CD33  POWER  = PVDDCR_CPU1_P0
  CD34  VSS_CD34  POWER  = GND
  CD35  P3_TXN0  OUT  = P5E_CPU0_P3_TX_DN<0>
  CD36  P3_TXP0  OUT  = P5E_CPU0_P3_TX_DP<0>
  CD37  VSS_CD37  POWER  = GND
  CD39  VSS_CD39  POWER  = GND
  CD40  P1_RXP15  IN  = P5E_CPU0_P1_RX_DP<15>
  CD41  P1_RXN15  IN  = P5E_CPU0_P1_RX_DN<15>
  CD42  VSS_CD42  POWER  = GND
  CD43  VDDCR_CPU1_CD43  POWER  = PVDDCR_CPU1_P0
  CD44  VDDCR_CPU1_CD44  POWER  = PVDDCR_CPU1_P0
  CD45  VSS_CD45  POWER  = GND
  CD46  VDDCR_CPU1_CD46  POWER  = PVDDCR_CPU1_P0
  CD47  VDDCR_CPU1_CD47  POWER  = PVDDCR_CPU1_P0
  CD48  VSS_CD48  POWER  = GND
  CD49  VDDCR_CPU1_CD49  POWER  = PVDDCR_CPU1_P0
  CD50  VDDCR_CPU1_CD50  POWER  = PVDDCR_CPU1_P0
  CD51  VSS_CD51  POWER  = GND
  CD52  VDDCR_CPU1_CD52  POWER  = PVDDCR_CPU1_P0
  CD53  VDDCR_CPU1_CD53  POWER  = PVDDCR_CPU1_P0
  CD54  VSS_CD54  POWER  = GND
  CD55  MCB_DATA3  BI  = M_C_CPU0_SB_DQ<3>
  CD56  MCB_DQS_H0  BI  = M_C_CPU0_SB_DQS_DP<0>
  CD57  VDDIO_CD57  POWER  = PVDDIO_P0
  CD58  MDB_DATA3  BI  = M_D_CPU0_SB_DQ<3>
  CD59  VSS_CD59  POWER  = GND
  CD60  MDB_DQS_H0  BI  = M_D_CPU0_SB_DQS_DP<0>
  CD61  VSS_CD61  POWER  = GND
  CD62  MBB_DATA3  BI  = M_B_CPU0_SB_DQ<3>
  CD63  MBB_DQS_H0  BI  = M_B_CPU0_SB_DQS_DP<0>
  CD64  VDDIO_CD64  POWER  = PVDDIO_P0
  CD65  MFB_DATA3  BI  = M_F_CPU0_SB_DQ<3>
  CD66  VSS_CD66  POWER  = GND
  CD67  MFB_DQS_H0  BI  = M_F_CPU0_SB_DQS_DP<0>
  CD68  VSS_CD68  POWER  = GND
  CD69  MEB_DATA3  BI  = M_E_CPU0_SB_DQ<3>
  CD70  MEB_DQS_H0  BI  = M_E_CPU0_SB_DQS_DP<0>
  CD71  VDDIO_CD71  POWER  = PVDDIO_P0
  CD72  MAB_DATA3  BI  = M_A_CPU0_SB_DQ<3>
  CD73  VSS_CD73  POWER  = GND
  CD74  MAB_DQS_H0  BI  = M_A_CPU0_SB_DQS_DP<0>
  CE1  VSS_CE1  POWER  = GND
  CE2  MGB_DQS_L0  BI  = M_G_CPU0_SB_DQS_DN<0>
  CE3  MGB_DQS_L5  BI  = M_G_CPU0_SB_DQS_DN<5>
  CE4  VSS_CE4  POWER  = GND
  CE5  MKB_DQS_L0  BI  = M_K_CPU0_SB_DQS_DN<0>
  CE6  VSS_CE6  POWER  = GND
  CE7  MKB_DQS_L5  BI  = M_K_CPU0_SB_DQS_DN<5>
  CE8  VSS_CE8  POWER  = GND
  CE9  MLB_DQS_L0  BI  = M_L_CPU0_SB_DQS_DN<0>
  CE10  MLB_DQS_L5  BI  = M_L_CPU0_SB_DQS_DN<5>
  CE11  VSS_CE11  POWER  = GND
  CE12  MHB_DQS_L0  BI  = M_H_CPU0_SB_DQS_DN<0>
  CE13  VSS_CE13  POWER  = GND
  CE14  MHB_DQS_L5  BI  = M_H_CPU0_SB_DQS_DN<5>
  CE15  VSS_CE15  POWER  = GND
  CE16  MJB_DQS_L0  BI  = M_J_CPU0_SB_DQS_DN<0>
  CE17  MJB_DQS_L5  BI  = M_J_CPU0_SB_DQS_DN<5>
  CE18  VSS_CE18  POWER  = GND
  CE19  MIB_DQS_L0  BI  = M_I_CPU0_SB_DQS_DN<0>
  CE20  VSS_CE20  POWER  = GND
  CE21  MIB_DQS_L5  BI  = M_I_CPU0_SB_DQS_DN<5>
  CE22  VSS_CE22  POWER  = GND
  CE23  P3_TXN15  OUT  = P5E_CPU0_P3_TX_DN<15>
  CE24  P3_TXP15  OUT  = P5E_CPU0_P3_TX_DP<15>
  CE25  VSS_CE25  POWER  = GND
  CE26  P3_TXN12  OUT  = P5E_CPU0_P3_TX_DN<12>
  CE27  P3_TXP12  OUT  = P5E_CPU0_P3_TX_DP<12>
  CE28  VSS_CE28  POWER  = GND
  CE29  P3_TXN9  OUT  = P5E_CPU0_P3_TX_DN<9>
  CE30  P3_TXP9  OUT  = P5E_CPU0_P3_TX_DP<9>
  CE31  VSS_CE31  POWER  = GND
  CE32  P3_TXN6  OUT  = P5E_CPU0_P3_TX_DN<6>
  CE33  P3_TXP6  OUT  = P5E_CPU0_P3_TX_DP<6>
  CE34  VSS_CE34  POWER  = GND
  CE35  VSS_CE35  POWER  = GND
  CE36  VSS_CE36  POWER  = GND
  CE40  VSS_CE40  POWER  = GND
  CE41  VSS_CE41  POWER  = GND
  CE42  VSS_CE42  POWER  = GND
  CE43  P1_RXP9  IN  = P5E_CPU0_P1_RX_DP<9>
  CE44  P1_RXN9  IN  = P5E_CPU0_P1_RX_DN<9>
  CE45  VSS_CE45  POWER  = GND
  CE46  P1_RXP6  IN  = P5E_CPU0_P1_RX_DP<6>
  CE47  P1_RXN6  IN  = P5E_CPU0_P1_RX_DN<6>
  CE48  VSS_CE48  POWER  = GND
  CE49  P1_RXP3  IN  = P5E_CPU0_P1_RX_DP<3>
  CE50  P1_RXN3  IN  = P5E_CPU0_P1_RX_DN<3>
  CE51  VSS_CE51  POWER  = GND
  CE52  P1_RXP0  IN  = P5E_CPU0_P1_RX_DP<0>
  CE53  P1_RXN0  IN  = P5E_CPU0_P1_RX_DN<0>
  CE54  VSS_CE54  POWER  = GND
  CE55  MCB_DQS_L5  BI  = M_C_CPU0_SB_DQS_DN<5>
  CE56  VSS_CE56  POWER  = GND
  CE57  MCB_DQS_L0  BI  = M_C_CPU0_SB_DQS_DN<0>
  CE58  VSS_CE58  POWER  = GND
  CE59  MDB_DQS_L5  BI  = M_D_CPU0_SB_DQS_DN<5>
  CE60  MDB_DQS_L0  BI  = M_D_CPU0_SB_DQS_DN<0>
  CE61  VSS_CE61  POWER  = GND
  CE62  MBB_DQS_L5  BI  = M_B_CPU0_SB_DQS_DN<5>
  CE63  VSS_CE63  POWER  = GND
  CE64  MBB_DQS_L0  BI  = M_B_CPU0_SB_DQS_DN<0>
  CE65  VSS_CE65  POWER  = GND
  CE66  MFB_DQS_L5  BI  = M_F_CPU0_SB_DQS_DN<5>
  CE67  MFB_DQS_L0  BI  = M_F_CPU0_SB_DQS_DN<0>
  CE68  VSS_CE68  POWER  = GND
  CE69  MEB_DQS_L5  BI  = M_E_CPU0_SB_DQS_DN<5>
  CE70  VSS_CE70  POWER  = GND
  CE71  MEB_DQS_L0  BI  = M_E_CPU0_SB_DQS_DN<0>
  CE72  VSS_CE72  POWER  = GND
  CE73  MAB_DQS_L5  BI  = M_A_CPU0_SB_DQS_DN<5>
  CE74  MAB_DQS_L0  BI  = M_A_CPU0_SB_DQS_DN<0>
  CE75  VSS_CE75  POWER  = GND
  CF2  MGB_DATA4  BI  = M_G_CPU0_SB_DQ<4>
  CF3  VSS_CF3  POWER  = GND
  CF4  MGB_DQS_H5  BI  = M_G_CPU0_SB_DQS_DP<5>
  CF5  VSS_CF5  POWER  = GND
  CF6  MKB_DATA4  BI  = M_K_CPU0_SB_DQ<4>
  CF7  MKB_DQS_H5  BI  = M_K_CPU0_SB_DQS_DP<5>
  CF8  VSS_CF8  POWER  = GND
  CF9  MLB_DATA4  BI  = M_L_CPU0_SB_DQ<4>
  CF10  VSS_CF10  POWER  = GND
  CF11  MLB_DQS_H5  BI  = M_L_CPU0_SB_DQS_DP<5>
  CF12  VSS_CF12  POWER  = GND
  CF13  MHB_DATA4  BI  = M_H_CPU0_SB_DQ<4>
  CF14  MHB_DQS_H5  BI  = M_H_CPU0_SB_DQS_DP<5>
  CF15  VSS_CF15  POWER  = GND
  CF16  MJB_DATA4  BI  = M_J_CPU0_SB_DQ<4>
  CF17  VSS_CF17  POWER  = GND
  CF18  MJB_DQS_H5  BI  = M_J_CPU0_SB_DQS_DP<5>
  CF19  VSS_CF19  POWER  = GND
  CF20  MIB_DATA4  BI  = M_I_CPU0_SB_DQ<4>
  CF21  MIB_DQS_H5  BI  = M_I_CPU0_SB_DQS_DP<5>
  CF22  VDD_11_S3_CF22  POWER  = PVDD11_S3_P0
  CF23  VSS_CF23  POWER  = GND
  CF24  VSS_CF24  POWER  = GND
  CF25  VSS_CF25  POWER  = GND
  CF26  VSS_CF26  POWER  = GND
  CF27  VSS_CF27  POWER  = GND
  CF28  VSS_CF28  POWER  = GND
  CF29  VSS_CF29  POWER  = GND
  CF30  VSS_CF30  POWER  = GND
  CF31  VSS_CF31  POWER  = GND
  CF32  VSS_CF32  POWER  = GND
  CF33  VSS_CF33  POWER  = GND
  CF34  VSS_CF34  POWER  = GND
  CF35  P3_TXN1  OUT  = P5E_CPU0_P3_TX_DN<1>
  CF36  P3_TXP1  OUT  = P5E_CPU0_P3_TX_DP<1>
  CF37  VSS_CF37  POWER  = GND
  CF39  VSS_CF39  POWER  = GND
  CF40  P1_RXP14  IN  = P5E_CPU0_P1_RX_DP<14>
  CF41  P1_RXN14  IN  = P5E_CPU0_P1_RX_DN<14>
  CF42  VSS_CF42  POWER  = GND
  CF43  VSS_CF43  POWER  = GND
  CF44  VSS_CF44  POWER  = GND
  CF45  VSS_CF45  POWER  = GND
  CF46  VSS_CF46  POWER  = GND
  CF47  VSS_CF47  POWER  = GND
  CF48  VSS_CF48  POWER  = GND
  CF49  VSS_CF49  POWER  = GND
  CF50  VSS_CF50  POWER  = GND
  CF51  VSS_CF51  POWER  = GND
  CF52  VSS_CF52  POWER  = GND
  CF53  VSS_CF53  POWER  = GND
  CF54  VDDIO_CF54  POWER  = PVDDIO_P0
  CF55  MCB_DQS_H5  BI  = M_C_CPU0_SB_DQS_DP<5>
  CF56  MCB_DATA4  BI  = M_C_CPU0_SB_DQ<4>
  CF57  VSS_CF57  POWER  = GND
  CF58  MDB_DQS_H5  BI  = M_D_CPU0_SB_DQS_DP<5>
  CF59  VSS_CF59  POWER  = GND
  CF60  MDB_DATA4  BI  = M_D_CPU0_SB_DQ<4>
  CF61  VSS_CF61  POWER  = GND
  CF62  MBB_DQS_H5  BI  = M_B_CPU0_SB_DQS_DP<5>
  CF63  MBB_DATA4  BI  = M_B_CPU0_SB_DQ<4>
  CF64  VSS_CF64  POWER  = GND
  CF65  MFB_DQS_H5  BI  = M_F_CPU0_SB_DQS_DP<5>
  CF66  VSS_CF66  POWER  = GND
  CF67  MFB_DATA4  BI  = M_F_CPU0_SB_DQ<4>
  CF68  VSS_CF68  POWER  = GND
  CF69  MEB_DQS_H5  BI  = M_E_CPU0_SB_DQS_DP<5>
  CF70  MEB_DATA4  BI  = M_E_CPU0_SB_DQ<4>
  CF71  VSS_CF71  POWER  = GND
  CF72  MAB_DQS_H5  BI  = M_A_CPU0_SB_DQS_DP<5>
  CF73  VSS_CF73  POWER  = GND
  CF74  MAB_DATA4  BI  = M_A_CPU0_SB_DQ<4>
  CG1  VSS_CG1  POWER  = GND
  CG2  MGB_DATA6  BI  = M_G_CPU0_SB_DQ<6>
  CG3  MGB_DATA5  BI  = M_G_CPU0_SB_DQ<5>
  CG4  VDD_11_S3_CG4  POWER  = PVDD11_S3_P0
  CG5  MKB_DATA6  BI  = M_K_CPU0_SB_DQ<6>
  CG6  VSS_CG6  POWER  = GND
  CG7  MKB_DATA5  BI  = M_K_CPU0_SB_DQ<5>
  CG8  VSS_CG8  POWER  = GND
  CG9  MLB_DATA6  BI  = M_L_CPU0_SB_DQ<6>
  CG10  MLB_DATA5  BI  = M_L_CPU0_SB_DQ<5>
  CG11  VDD_11_S3_CG11  POWER  = PVDD11_S3_P0
  CG12  MHB_DATA6  BI  = M_H_CPU0_SB_DQ<6>
  CG13  VSS_CG13  POWER  = GND
  CG14  MHB_DATA5  BI  = M_H_CPU0_SB_DQ<5>
  CG15  VSS_CG15  POWER  = GND
  CG16  MJB_DATA6  BI  = M_J_CPU0_SB_DQ<6>
  CG17  MJB_DATA5  BI  = M_J_CPU0_SB_DQ<5>
  CG18  VDD_11_S3_CG18  POWER  = PVDD11_S3_P0
  CG19  MIB_DATA6  BI  = M_I_CPU0_SB_DQ<6>
  CG20  VSS_CG20  POWER  = GND
  CG21  MIB_DATA5  BI  = M_I_CPU0_SB_DQ<5>
  CG22  VSS_CG22  POWER  = GND
  CG23  P3_TXN14  OUT  = P5E_CPU0_P3_TX_DN<14>
  CG24  P3_TXP14  OUT  = P5E_CPU0_P3_TX_DP<14>
  CG25  VSS_CG25  POWER  = GND
  CG26  P3_TXN11  OUT  = P5E_CPU0_P3_TX_DN<11>
  CG27  P3_TXP11  OUT  = P5E_CPU0_P3_TX_DP<11>
  CG28  VSS_CG28  POWER  = GND
  CG29  P3_TXN8  OUT  = P5E_CPU0_P3_TX_DN<8>
  CG30  P3_TXP8  OUT  = P5E_CPU0_P3_TX_DP<8>
  CG31  VSS_CG31  POWER  = GND
  CG32  P3_TXN5  OUT  = P5E_CPU0_P3_TX_DN<5>
  CG33  P3_TXP5  OUT  = P5E_CPU0_P3_TX_DP<5>
  CG34  VSS_CG34  POWER  = GND
  CG35  VDDCR_CPU1_CG35  POWER  = PVDDCR_CPU1_P0
  CG36  VDDCR_CPU1_CG36  POWER  = PVDDCR_CPU1_P0
  CG40  VDDCR_CPU1_CG40  POWER  = PVDDCR_CPU1_P0
  CG41  VDDCR_CPU1_CG41  POWER  = PVDDCR_CPU1_P0
  CG42  VSS_CG42  POWER  = GND
  CG43  P1_RXP10  IN  = P5E_CPU0_P1_RX_DP<10>
  CG44  P1_RXN10  IN  = P5E_CPU0_P1_RX_DN<10>
  CG45  VSS_CG45  POWER  = GND
  CG46  P1_RXP7  IN  = P5E_CPU0_P1_RX_DP<7>
  CG47  P1_RXN7  IN  = P5E_CPU0_P1_RX_DN<7>
  CG48  VSS_CG48  POWER  = GND
  CG49  P1_RXP4  IN  = P5E_CPU0_P1_RX_DP<4>
  CG50  P1_RXN4  IN  = P5E_CPU0_P1_RX_DN<4>
  CG51  VSS_CG51  POWER  = GND
  CG52  P1_RXP1  IN  = P5E_CPU0_P1_RX_DP<1>
  CG53  P1_RXN1  IN  = P5E_CPU0_P1_RX_DN<1>
  CG54  VSS_CG54  POWER  = GND
  CG55  MCB_DATA5  BI  = M_C_CPU0_SB_DQ<5>
  CG56  VSS_CG56  POWER  = GND
  CG57  MCB_DATA6  BI  = M_C_CPU0_SB_DQ<6>
  CG58  VDDIO_CG58  POWER  = PVDDIO_P0
  CG59  MDB_DATA5  BI  = M_D_CPU0_SB_DQ<5>
  CG60  MDB_DATA6  BI  = M_D_CPU0_SB_DQ<6>
  CG61  VSS_CG61  POWER  = GND
  CG62  MBB_DATA5  BI  = M_B_CPU0_SB_DQ<5>
  CG63  VSS_CG63  POWER  = GND
  CG64  MBB_DATA6  BI  = M_B_CPU0_SB_DQ<6>
  CG65  VDDIO_CG65  POWER  = PVDDIO_P0
  CG66  MFB_DATA5  BI  = M_F_CPU0_SB_DQ<5>
  CG67  MFB_DATA6  BI  = M_F_CPU0_SB_DQ<6>
  CG68  VSS_CG68  POWER  = GND
  CG69  MEB_DATA5  BI  = M_E_CPU0_SB_DQ<5>
  CG70  VSS_CG70  POWER  = GND
  CG71  MEB_DATA6  BI  = M_E_CPU0_SB_DQ<6>
  CG72  VDDIO_CG72  POWER  = PVDDIO_P0
  CG73  MAB_DATA5  BI  = M_A_CPU0_SB_DQ<5>
  CG74  MAB_DATA6  BI  = M_A_CPU0_SB_DQ<6>
  CG75  VSS_CG75  POWER  = GND
  CH2  MGB_DATA8  BI  = M_G_CPU0_SB_DQ<8>
  CH3  VSS_CH3  POWER  = GND
  CH4  MGB_DATA7  BI  = M_G_CPU0_SB_DQ<7>
  CH5  VSS_CH5  POWER  = GND
  CH6  MKB_DATA8  BI  = M_K_CPU0_SB_DQ<8>
  CH7  MKB_DATA7  BI  = M_K_CPU0_SB_DQ<7>
  CH8  VSS_CH8  POWER  = GND
  CH9  MLB_DATA8  BI  = M_L_CPU0_SB_DQ<8>
  CH10  VSS_CH10  POWER  = GND
  CH11  MLB_DATA7  BI  = M_L_CPU0_SB_DQ<7>
  CH12  VSS_CH12  POWER  = GND
  CH13  MHB_DATA8  BI  = M_H_CPU0_SB_DQ<8>
  CH14  MHB_DATA7  BI  = M_H_CPU0_SB_DQ<7>
  CH15  VSS_CH15  POWER  = GND
  CH16  MJB_DATA8  BI  = M_J_CPU0_SB_DQ<8>
  CH17  VSS_CH17  POWER  = GND
  CH18  MJB_DATA7  BI  = M_J_CPU0_SB_DQ<7>
  CH19  VSS_CH19  POWER  = GND
  CH20  MIB_DATA8  BI  = M_I_CPU0_SB_DQ<8>
  CH21  MIB_DATA7  BI  = M_I_CPU0_SB_DQ<7>
  CH22  VSS_CH22  POWER  = GND
  CH23  VDDCR_CPU1_CH23  POWER  = PVDDCR_CPU1_P0
  CH24  VDDCR_CPU1_CH24  POWER  = PVDDCR_CPU1_P0
  CH25  VSS_CH25  POWER  = GND
  CH26  VDDCR_CPU1_CH26  POWER  = PVDDCR_CPU1_P0
  CH27  VDDCR_CPU1_CH27  POWER  = PVDDCR_CPU1_P0
  CH28  VSS_CH28  POWER  = GND
  CH29  VDDCR_CPU1_CH29  POWER  = PVDDCR_CPU1_P0
  CH30  VDDCR_CPU1_CH30  POWER  = PVDDCR_CPU1_P0
  CH31  VSS_CH31  POWER  = GND
  CH32  VDDCR_CPU1_CH32  POWER  = PVDDCR_CPU1_P0
  CH33  VDDCR_CPU1_CH33  POWER  = PVDDCR_CPU1_P0
  CH34  VSS_CH34  POWER  = GND
  CH35  P3_TXN2  OUT  = P5E_CPU0_P3_TX_DN<2>
  CH36  P3_TXP2  OUT  = P5E_CPU0_P3_TX_DP<2>
  CH37  VSS_CH37  POWER  = GND
  CH39  VSS_CH39  POWER  = GND
  CH40  P1_RXP13  IN  = P5E_CPU0_P1_RX_DP<13>
  CH41  P1_RXN13  IN  = P5E_CPU0_P1_RX_DN<13>
  CH42  VSS_CH42  POWER  = GND
  CH43  VDDCR_CPU1_CH43  POWER  = PVDDCR_CPU1_P0
  CH44  VDDCR_CPU1_CH44  POWER  = PVDDCR_CPU1_P0
  CH45  VSS_CH45  POWER  = GND
  CH46  VDDCR_CPU1_CH46  POWER  = PVDDCR_CPU1_P0
  CH47  VDDCR_CPU1_CH47  POWER  = PVDDCR_CPU1_P0
  CH48  VSS_CH48  POWER  = GND
  CH49  VDDCR_CPU1_CH49  POWER  = PVDDCR_CPU1_P0
  CH50  VDDCR_CPU1_CH50  POWER  = PVDDCR_CPU1_P0
  CH51  VSS_CH51  POWER  = GND
  CH52  VDDCR_CPU1_CH52  POWER  = PVDDCR_CPU1_P0
  CH53  VDDCR_CPU1_CH53  POWER  = PVDDCR_CPU1_P0
  CH54  VSS_CH54  POWER  = GND
  CH55  MCB_DATA7  BI  = M_C_CPU0_SB_DQ<7>
  CH56  MCB_DATA8  BI  = M_C_CPU0_SB_DQ<8>
